(kicad_pcb
	(version 20260206)
	(generator "pcbnew")
	(generator_version "10.0")
	(general
		(thickness 1.6)
		(legacy_teardrops no)
	)
	(paper "A4")
	(title_block
		(title "Bryce Canyon_IOM_IOC_16318-2_OCP.brd")
		(comment 1 "Bryce Canyon / footprints 553-561 of 1605")
	)
	(layers
		(0 "F.Cu" signal "TOP")
		(4 "In1.Cu" signal "L2GND")
		(6 "In2.Cu" signal "L3")
		(8 "In3.Cu" signal "L4VCC")
		(10 "In4.Cu" signal "L5VCC")
		(12 "In5.Cu" signal "L6")
		(14 "In6.Cu" signal "L7GND")
		(2 "B.Cu" signal "BOTTOM")
		(9 "F.Adhes" user "F.Adhesive")
		(11 "B.Adhes" user "B.Adhesive")
		(13 "F.Paste" user "Package Geometry/Pastemask Top")
		(15 "B.Paste" user "Package Geometry/Pastemask Bottom")
		(5 "F.SilkS" user "Ref Des/Silkscreen Top")
		(7 "B.SilkS" user "Ref Des/Silkscreen Bottom")
		(1 "F.Mask" user "Board Geometry/Soldermask Top")
		(3 "B.Mask" user "Board Geometry/Soldermask Bottom")
		(17 "Dwgs.User" user "User.Drawings")
		(19 "Cmts.User" user "User.Comments")
		(21 "Eco1.User" user "User.Eco1")
		(23 "Eco2.User" user "User.Eco2")
		(25 "Edge.Cuts" user "Board Geometry/Outline")
		(27 "Margin" user)
		(31 "F.CrtYd" user "Package Geometry/Place Bound Top")
		(29 "B.CrtYd" user "Package Geometry/Place Bound Bottom")
		(35 "F.Fab" user "Ref Des/Assembly Top")
		(33 "B.Fab" user "Ref Des/Assembly Bottom")
	)
	(footprint ""
		(layer "F.Cu")
		(at 50.17897 -161.279078)
		(property "Reference" "R400"
			(at 0 0 0)
			(layer "F.SilkS")
			(hide yes)
			(effects
				(font
					(size 1.27 1.27)
				)
			)
		)
		(property "Value" "4K7R2F-GP"
			(at 0.064008 -3.993896 0)
			(unlocked yes)
			(layer "F.Fab")
			(hide yes)
			(effects
				(font
					(size 1.016 1.016)
					(thickness 0.1524)
				)
			)
		)
		(property "Device Type" "R402H16"
			(at 0.064008 -5.517896 0)
			(unlocked yes)
			(layer "F.Fab")
			(hide yes)
			(effects
				(font
					(size 1.016 1.016)
					(thickness 0.1524)
				)
			)
		)
		(duplicate_pad_numbers_are_jumpers no)
		(fp_line
			(start -0.508 -0.9398)
			(end -0.508 0.9398)
			(stroke
				(width 0.1524)
				(type default)
			)
			(layer "F.SilkS")
		)
		(fp_line
			(start 0.508 -0.9398)
			(end -0.508 -0.9398)
			(stroke
				(width 0.1524)
				(type default)
			)
			(layer "F.SilkS")
		)
		(fp_rect
			(start -0.508 0.9398)
			(end 0.508 -0.9398)
			(stroke
				(width 0)
				(type default)
			)
			(fill no)
			(layer "F.CrtYd")
		)
		(fp_rect
			(start -0.508 0.9398)
			(end 0.508 -0.9398)
			(stroke
				(width 0)
				(type default)
			)
			(fill no)
			(layer "F.Fab")
		)
		(pad "1" smd custom
			(at 0 -0.4445)
			(size 0.1397 0.1397)
			(layers "F.Cu" "F.Mask" "F.Paste")
			(net "GND")
			(options
				(clearance outline)
				(anchor circle)
			)
			(primitives
				(gr_poly
					(pts
						(arc
							(start -0.1778 -0.2794)
							(mid -0.249642 -0.249642)
							(end -0.2794 -0.1778)
						)
						(arc
							(start -0.2794 0.1778)
							(mid -0.249642 0.249642)
							(end -0.1778 0.2794)
						)
						(arc
							(start 0.1778 0.2794)
							(mid 0.249642 0.249642)
							(end 0.2794 0.1778)
						)
						(arc
							(start 0.2794 -0.1778)
							(mid 0.249642 -0.249642)
							(end 0.1778 -0.2794)
						)
					)
					(width 0)
					(fill yes)
				)
			)
		)
		(pad "2" smd custom
			(at 0 0.4445)
			(size 0.1397 0.1397)
			(layers "F.Cu" "F.Mask" "F.Paste")
			(net "UART_BMC_TX")
			(options
				(clearance outline)
				(anchor circle)
			)
			(primitives
				(gr_poly
					(pts
						(arc
							(start -0.1778 -0.2794)
							(mid -0.249642 -0.249642)
							(end -0.2794 -0.1778)
						)
						(arc
							(start -0.2794 0.1778)
							(mid -0.249642 0.249642)
							(end -0.1778 0.2794)
						)
						(arc
							(start 0.1778 0.2794)
							(mid 0.249642 0.249642)
							(end 0.2794 0.1778)
						)
						(arc
							(start 0.2794 -0.1778)
							(mid 0.249642 -0.249642)
							(end 0.1778 -0.2794)
						)
					)
					(width 0)
					(fill yes)
				)
			)
		)
	)
	(footprint ""
		(layer "F.Cu")
		(at 208.5467 -132.957316 180)
		(property "Reference" "C255"
			(at 0 0 180)
			(layer "F.SilkS")
			(hide yes)
			(effects
				(font
					(size 1.27 1.27)
				)
			)
		)
		(property "Value" "SC10U6D3V5KX-4GP"
			(at -0.0762 -6.1214 180)
			(unlocked yes)
			(layer "F.Fab")
			(hide yes)
			(effects
				(font
					(size 1.016 1.016)
					(thickness 0.1524)
				)
			)
		)
		(property "Device Type" "C805H58"
			(at -0.0762 -8.1534 180)
			(unlocked yes)
			(layer "F.Fab")
			(hide yes)
			(effects
				(font
					(size 1.016 1.016)
					(thickness 0.1524)
				)
			)
		)
		(duplicate_pad_numbers_are_jumpers no)
		(fp_line
			(start 0.635 0)
			(end -0.635 0)
			(stroke
				(width 0.508)
				(type default)
			)
			(layer "F.SilkS")
		)
		(fp_rect
			(start -0.9652 1.778)
			(end 0.9652 -1.778)
			(stroke
				(width 0)
				(type default)
			)
			(fill no)
			(layer "F.CrtYd")
		)
		(fp_poly
			(pts
				(xy -0.9652 -1.778) (xy 0.9652 -1.778) (xy 0.9652 1.778) (xy -0.9652 1.778)
			)
			(stroke
				(width 0)
				(type default)
			)
			(fill no)
			(layer "F.Fab")
		)
		(pad "1" smd rect
			(at 0 -0.9652 180)
			(size 1.397 1.143)
			(layers "F.Cu" "F.Mask" "F.Paste")
			(net "P1V8_STBY")
		)
		(pad "2" smd rect
			(at 0 0.9652 180)
			(size 1.397 1.143)
			(layers "F.Cu" "F.Mask" "F.Paste")
			(net "GND")
		)
	)
	(footprint ""
		(layer "F.Cu")
		(at 202.698096 -10.668 -90)
		(property "Reference" "R817"
			(at 0 0 270)
			(layer "F.SilkS")
			(hide yes)
			(effects
				(font
					(size 1.27 1.27)
				)
			)
		)
		(property "Value" "130R3F-GP"
			(at -0.0254 -2.5146 270)
			(unlocked yes)
			(layer "F.Fab")
			(hide yes)
			(effects
				(font
					(size 1.016 1.016)
					(thickness 0.1524)
				)
			)
		)
		(property "Device Type" "R603H22"
			(at -0.0254 -4.0386 270)
			(unlocked yes)
			(layer "F.Fab")
			(hide yes)
			(effects
				(font
					(size 1.016 1.016)
					(thickness 0.1524)
				)
			)
		)
		(duplicate_pad_numbers_are_jumpers no)
		(fp_line
			(start -0.4826 0)
			(end -0.2032 0)
			(stroke
				(width 0.2032)
				(type default)
			)
			(layer "F.SilkS")
		)
		(fp_line
			(start 0.2032 0)
			(end 0.4826 0)
			(stroke
				(width 0.2032)
				(type default)
			)
			(layer "F.SilkS")
		)
		(fp_rect
			(start -0.5842 1.3335)
			(end 0.5842 -1.3335)
			(stroke
				(width 0)
				(type default)
			)
			(fill no)
			(layer "F.CrtYd")
		)
		(fp_rect
			(start -0.5842 1.3335)
			(end 0.5842 -1.3335)
			(stroke
				(width 0)
				(type default)
			)
			(fill no)
			(layer "F.Fab")
		)
		(pad "1" smd custom
			(at 0 -0.762 270)
			(size 0.2159 0.2159)
			(layers "F.Cu" "F.Mask" "F.Paste")
			(net "ML_PWR_BLUE_LED_R")
			(options
				(clearance outline)
				(anchor circle)
			)
			(primitives
				(gr_poly
					(pts
						(arc
							(start -0.3302 -0.4318)
							(mid -0.402042 -0.402042)
							(end -0.4318 -0.3302)
						)
						(arc
							(start -0.4318 0.3302)
							(mid -0.402042 0.402042)
							(end -0.3302 0.4318)
						)
						(arc
							(start 0.3302 0.4318)
							(mid 0.402042 0.402042)
							(end 0.4318 0.3302)
						)
						(arc
							(start 0.4318 -0.3302)
							(mid 0.402042 -0.402042)
							(end 0.3302 -0.4318)
						)
					)
					(width 0)
					(fill yes)
				)
			)
		)
		(pad "2" smd custom
			(at 0 0.762 270)
			(size 0.2159 0.2159)
			(layers "F.Cu" "F.Mask" "F.Paste")
			(net "ML_PWR_BLUE_LED")
			(options
				(clearance outline)
				(anchor circle)
			)
			(primitives
				(gr_poly
					(pts
						(arc
							(start -0.3302 -0.4318)
							(mid -0.402042 -0.402042)
							(end -0.4318 -0.3302)
						)
						(arc
							(start -0.4318 0.3302)
							(mid -0.402042 0.402042)
							(end -0.3302 0.4318)
						)
						(arc
							(start 0.3302 0.4318)
							(mid 0.402042 0.402042)
							(end 0.4318 0.3302)
						)
						(arc
							(start 0.4318 -0.3302)
							(mid 0.402042 -0.402042)
							(end 0.3302 -0.4318)
						)
					)
					(width 0)
					(fill yes)
				)
			)
		)
	)
	(footprint ""
		(layer "F.Cu")
		(at 156.5402 -38.4556)
		(property "Reference" "TP179"
			(at 0 0 0)
			(layer "F.SilkS")
			(hide yes)
			(effects
				(font
					(size 1.27 1.27)
				)
			)
		)
		(property "Value" "TPAD28-2-GP"
			(at -0.0127 -1.6637 0)
			(unlocked yes)
			(layer "F.Fab")
			(hide yes)
			(effects
				(font
					(size 1.016 1.016)
					(thickness 0.1524)
				)
			)
		)
		(property "Device Type" "TPAD28"
			(at -0.0127 -3.1877 0)
			(unlocked yes)
			(layer "F.Fab")
			(hide yes)
			(effects
				(font
					(size 1.016 1.016)
					(thickness 0.1524)
				)
			)
		)
		(duplicate_pad_numbers_are_jumpers no)
		(fp_poly
			(pts
				(arc
					(start 0.3556 0)
					(mid -0.3556 0)
					(end 0.3556 0)
				)
			)
			(stroke
				(width 0)
				(type default)
			)
			(fill no)
			(layer "F.CrtYd")
		)
		(fp_poly
			(pts
				(arc
					(start 0.6096 0)
					(mid -0.6096 0)
					(end 0.6096 0)
				)
			)
			(stroke
				(width 0)
				(type default)
			)
			(fill no)
			(layer "F.Fab")
		)
		(pad "1" smd circle
			(at 0 0)
			(size 0.7112 0.7112)
			(layers "F.Cu" "F.Mask" "F.Paste")
			(net "ZDEF_EXTB_TP_C1")
		)
	)
	(footprint ""
		(layer "F.Cu")
		(at 226.983036 -96.814386)
		(property "Reference" "L21"
			(at 0 0 0)
			(layer "F.SilkS")
			(hide yes)
			(effects
				(font
					(size 1.27 1.27)
				)
			)
		)
		(property "Value" "28F0181-1SR-10-GP"
			(at -4.064 -3.5052 0)
			(unlocked yes)
			(layer "F.Fab")
			(hide yes)
			(effects
				(font
					(size 1.016 1.016)
					(thickness 0.1524)
				)
			)
		)
		(property "Device Type" "L9546-152127H121"
			(at -4.064 -5.0292 0)
			(unlocked yes)
			(layer "F.Fab")
			(hide yes)
			(effects
				(font
					(size 1.016 1.016)
					(thickness 0.1524)
				)
			)
		)
		(duplicate_pad_numbers_are_jumpers no)
		(fp_line
			(start -2.54 -5.6642)
			(end -2.54 5.6642)
			(stroke
				(width 0.1524)
				(type default)
			)
			(layer "F.SilkS")
		)
		(fp_line
			(start -2.54 5.6642)
			(end 2.54 5.6642)
			(stroke
				(width 0.1524)
				(type default)
			)
			(layer "F.SilkS")
		)
		(fp_line
			(start 2.54 -5.6642)
			(end -2.54 -5.6642)
			(stroke
				(width 0.1524)
				(type default)
			)
			(layer "F.SilkS")
		)
		(fp_line
			(start 2.54 5.6642)
			(end 2.54 -5.6642)
			(stroke
				(width 0.1524)
				(type default)
			)
			(layer "F.SilkS")
		)
		(fp_rect
			(start -2.286 4.7625)
			(end 2.286 -4.7625)
			(stroke
				(width 0)
				(type default)
			)
			(fill no)
			(layer "F.CrtYd")
		)
		(fp_poly
			(pts
				(xy -2.794 5.7404) (xy -2.794 -5.7404) (xy 2.794 -5.7404) (xy 2.794 5.7404) (xy 0.00254 5.7404)
				(xy 0.00254 4.7625) (xy 2.286 4.7625) (xy 2.286 -4.7625) (xy -2.286 -4.7625) (xy -2.286 4.7625)
				(xy -0.00254 4.7625) (xy -0.00254 5.7404)
			)
			(stroke
				(width 0)
				(type default)
			)
			(fill no)
			(layer "F.CrtYd")
		)
		(fp_rect
			(start -2.794 5.7404)
			(end 2.794 -5.7404)
			(stroke
				(width 0)
				(type default)
			)
			(fill no)
			(layer "F.Fab")
		)
		(pad "1" smd rect
			(at 0 -4.197604)
			(size 1.524 2.413)
			(layers "F.Cu" "F.Mask" "F.Paste")
			(net "P0V975")
		)
		(pad "2" smd rect
			(at 0 4.197604)
			(size 1.524 2.413)
			(layers "F.Cu" "F.Mask" "F.Paste")
			(net "SAS0_AVDD")
		)
	)
	(footprint ""
		(layer "F.Cu")
		(at 132.08 -27.6098)
		(property "Reference" "TP1"
			(at 0 0 0)
			(layer "F.SilkS")
			(hide yes)
			(effects
				(font
					(size 1.27 1.27)
				)
			)
		)
		(property "Value" "TPAD28-2-GP"
			(at -0.0127 -1.6637 0)
			(unlocked yes)
			(layer "F.Fab")
			(hide yes)
			(effects
				(font
					(size 1.016 1.016)
					(thickness 0.1524)
				)
			)
		)
		(property "Device Type" "TPAD28"
			(at -0.0127 -3.1877 0)
			(unlocked yes)
			(layer "F.Fab")
			(hide yes)
			(effects
				(font
					(size 1.016 1.016)
					(thickness 0.1524)
				)
			)
		)
		(duplicate_pad_numbers_are_jumpers no)
		(fp_poly
			(pts
				(arc
					(start 0.3556 0)
					(mid -0.3556 0)
					(end 0.3556 0)
				)
			)
			(stroke
				(width 0)
				(type default)
			)
			(fill no)
			(layer "F.CrtYd")
		)
		(fp_poly
			(pts
				(arc
					(start 0.6096 0)
					(mid -0.6096 0)
					(end 0.6096 0)
				)
			)
			(stroke
				(width 0)
				(type default)
			)
			(fill no)
			(layer "F.Fab")
		)
		(pad "1" smd circle
			(at 0 0)
			(size 0.7112 0.7112)
			(layers "F.Cu" "F.Mask" "F.Paste")
			(net "PCIE_COMP_TO_IOM_CLK_3_DN")
		)
	)
	(footprint ""
		(layer "F.Cu")
		(at 168.6306 -103.9876 -90)
		(property "Reference" "C461"
			(at 0 0 270)
			(layer "F.SilkS")
			(hide yes)
			(effects
				(font
					(size 1.27 1.27)
				)
			)
		)
		(property "Value" "SC1U16V2KX-7-GP"
			(at 1.7526 -1.6002 270)
			(unlocked yes)
			(layer "F.Fab")
			(hide yes)
			(effects
				(font
					(size 1.016 1.016)
					(thickness 0.1524)
				)
			)
		)
		(property "Device Type" "C402-TO0D2H24"
			(at 1.7526 -3.1242 270)
			(unlocked yes)
			(layer "F.Fab")
			(hide yes)
			(effects
				(font
					(size 1.016 1.016)
					(thickness 0.1524)
				)
			)
		)
		(duplicate_pad_numbers_are_jumpers no)
		(fp_rect
			(start -0.4826 0.889)
			(end 0.4826 -0.889)
			(stroke
				(width 0)
				(type default)
			)
			(fill no)
			(layer "F.CrtYd")
		)
		(fp_rect
			(start -0.4826 0.889)
			(end 0.4826 -0.889)
			(stroke
				(width 0)
				(type default)
			)
			(fill no)
			(layer "F.Fab")
		)
		(pad "1" smd custom
			(at 0 -0.4572 270)
			(size 0.1524 0.1524)
			(layers "F.Cu" "F.Mask" "F.Paste")
			(net "P1V8")
			(options
				(clearance outline)
				(anchor circle)
			)
			(primitives
				(gr_poly
					(pts
						(arc
							(start -0.254 0.3048)
							(mid -0.325842 0.275042)
							(end -0.3556 0.2032)
						)
						(arc
							(start -0.3556 -0.2032)
							(mid -0.325842 -0.275042)
							(end -0.254 -0.3048)
						)
						(arc
							(start 0.254 -0.3048)
							(mid 0.325842 -0.275042)
							(end 0.3556 -0.2032)
						)
						(arc
							(start 0.3556 0.2032)
							(mid 0.325842 0.275042)
							(end 0.254 0.3048)
						)
					)
					(width 0)
					(fill yes)
				)
			)
		)
		(pad "2" smd custom
			(at 0 0.4572 270)
			(size 0.1524 0.1524)
			(layers "F.Cu" "F.Mask" "F.Paste")
			(net "GND")
			(options
				(clearance outline)
				(anchor circle)
			)
			(primitives
				(gr_poly
					(pts
						(arc
							(start -0.254 0.3048)
							(mid -0.325842 0.275042)
							(end -0.3556 0.2032)
						)
						(arc
							(start -0.3556 -0.2032)
							(mid -0.325842 -0.275042)
							(end -0.254 -0.3048)
						)
						(arc
							(start 0.254 -0.3048)
							(mid 0.325842 -0.275042)
							(end 0.3556 -0.2032)
						)
						(arc
							(start 0.3556 0.2032)
							(mid 0.325842 0.275042)
							(end 0.254 0.3048)
						)
					)
					(width 0)
					(fill yes)
				)
			)
		)
	)
	(footprint ""
		(layer "F.Cu")
		(at 38.128448 -130.758692 180)
		(property "Reference" "R377"
			(at 0 0 180)
			(layer "F.SilkS")
			(hide yes)
			(effects
				(font
					(size 1.27 1.27)
				)
			)
		)
		(property "Value" "4K7R2F-GP"
			(at 0.064008 -3.993896 180)
			(unlocked yes)
			(layer "F.Fab")
			(hide yes)
			(effects
				(font
					(size 1.016 1.016)
					(thickness 0.1524)
				)
			)
		)
		(property "Device Type" "R402H16"
			(at 0.064008 -5.517896 180)
			(unlocked yes)
			(layer "F.Fab")
			(hide yes)
			(effects
				(font
					(size 1.016 1.016)
					(thickness 0.1524)
				)
			)
		)
		(duplicate_pad_numbers_are_jumpers no)
		(fp_line
			(start 0.508 -0.9398)
			(end -0.508 -0.9398)
			(stroke
				(width 0.1524)
				(type default)
			)
			(layer "F.SilkS")
		)
		(fp_line
			(start -0.508 -0.9398)
			(end -0.508 0.9398)
			(stroke
				(width 0.1524)
				(type default)
			)
			(layer "F.SilkS")
		)
		(fp_rect
			(start -0.508 0.9398)
			(end 0.508 -0.9398)
			(stroke
				(width 0)
				(type default)
			)
			(fill no)
			(layer "F.CrtYd")
		)
		(fp_rect
			(start -0.508 0.9398)
			(end 0.508 -0.9398)
			(stroke
				(width 0)
				(type default)
			)
			(fill no)
			(layer "F.Fab")
		)
		(pad "1" smd custom
			(at 0 -0.4445 180)
			(size 0.1397 0.1397)
			(layers "F.Cu" "F.Mask" "F.Paste")
			(net "P3V3_STBY")
			(options
				(clearance outline)
				(anchor circle)
			)
			(primitives
				(gr_poly
					(pts
						(arc
							(start -0.1778 -0.2794)
							(mid -0.249642 -0.249642)
							(end -0.2794 -0.1778)
						)
						(arc
							(start -0.2794 0.1778)
							(mid -0.249642 0.249642)
							(end -0.1778 0.2794)
						)
						(arc
							(start 0.1778 0.2794)
							(mid 0.249642 0.249642)
							(end 0.2794 0.1778)
						)
						(arc
							(start 0.2794 -0.1778)
							(mid 0.249642 -0.249642)
							(end 0.1778 -0.2794)
						)
					)
					(width 0)
					(fill yes)
				)
			)
		)
		(pad "2" smd custom
			(at 0 0.4445 180)
			(size 0.1397 0.1397)
			(layers "F.Cu" "F.Mask" "F.Paste")
			(net "BMC_GPIOZ5")
			(options
				(clearance outline)
				(anchor circle)
			)
			(primitives
				(gr_poly
					(pts
						(arc
							(start -0.1778 -0.2794)
							(mid -0.249642 -0.249642)
							(end -0.2794 -0.1778)
						)
						(arc
							(start -0.2794 0.1778)
							(mid -0.249642 0.249642)
							(end -0.1778 0.2794)
						)
						(arc
							(start 0.1778 0.2794)
							(mid 0.249642 0.249642)
							(end 0.2794 0.1778)
						)
						(arc
							(start 0.2794 -0.1778)
							(mid 0.249642 -0.249642)
							(end 0.1778 -0.2794)
						)
					)
					(width 0)
					(fill yes)
				)
			)
		)
	)
	(footprint ""
		(layer "F.Cu")
		(at 184.0738 -49.9872)
		(property "Reference" "TP165"
			(at 0 0 0)
			(layer "F.SilkS")
			(hide yes)
			(effects
				(font
					(size 1.27 1.27)
				)
			)
		)
		(property "Value" "TPAD28-2-GP"
			(at -0.0127 -1.6637 0)
			(unlocked yes)
			(layer "F.Fab")
			(hide yes)
			(effects
				(font
					(size 1.016 1.016)
					(thickness 0.1524)
				)
			)
		)
		(property "Device Type" "TPAD28"
			(at -0.0127 -3.1877 0)
			(unlocked yes)
			(layer "F.Fab")
			(hide yes)
			(effects
				(font
					(size 1.016 1.016)
					(thickness 0.1524)
				)
			)
		)
		(duplicate_pad_numbers_are_jumpers no)
		(fp_poly
			(pts
				(arc
					(start 0.3556 0)
					(mid -0.3556 0)
					(end 0.3556 0)
				)
			)
			(stroke
				(width 0)
				(type default)
			)
			(fill no)
			(layer "F.CrtYd")
		)
		(fp_poly
			(pts
				(arc
					(start 0.6096 0)
					(mid -0.6096 0)
					(end 0.6096 0)
				)
			)
			(stroke
				(width 0)
				(type default)
			)
			(fill no)
			(layer "F.Fab")
		)
		(pad "1" smd circle
			(at 0 0)
			(size 0.7112 0.7112)
			(layers "F.Cu" "F.Mask" "F.Paste")
			(net "XM_ALE")
		)
	)
)
